# T6G (Grand Teton) — schematic netlist excerpt (pin names and nets, part order shuffled) for the footprints in the layout excerpt that follows; sources: Cadence DE-HDL packaged netlist, KiCad conversion of 04192023_DAF0TMB3IC0_F0TG_MB_C_brd_V02_OCP.brd

R2474  Q_RES  0 5% EMPTY  pkg 0402LF  page 132 : A = FM_NCSI_OCP_SFF_R_OE ; B = FB_BMC_ISOLATE
R4070  Q_RES  10K 1% CHIP  pkg 0402LF  page 134 : A = P12V_AUX ; B = P3V3_OCP_1_EN_G

(kicad_pcb
	(version 20260206)
	(generator "pcbnew")
	(generator_version "10.0")
	(general
		(thickness 1.6)
		(legacy_teardrops no)
	)
	(paper "A4")
	(title_block
		(title "04192023_DAF0TMB3IC0_F0TG_MB_C_brd_V02_OCP.brd")
		(comment 1 "Grand Teton / footprints 2633-2634 of 8354")
	)
	(layers
		(0 "F.Cu" signal "TOP")
		(4 "In1.Cu" signal "GND")
		(6 "In2.Cu" signal "IN1")
		(8 "In3.Cu" signal "GND1")
		(10 "In4.Cu" signal "IN2")
		(12 "In5.Cu" signal "GND2")
		(14 "In6.Cu" signal "IN3")
		(16 "In7.Cu" signal "GND3")
		(18 "In8.Cu" signal "VCC")
		(20 "In9.Cu" signal "VCC1")
		(22 "In10.Cu" signal "GND4")
		(24 "In11.Cu" signal "IN4")
		(26 "In12.Cu" signal "GND5")
		(28 "In13.Cu" signal "IN5")
		(30 "In14.Cu" signal "GND6")
		(32 "In15.Cu" signal "IN6")
		(34 "In16.Cu" signal "GND7")
		(2 "B.Cu" signal "BOTTOM")
		(9 "F.Adhes" user "F.Adhesive")
		(11 "B.Adhes" user "B.Adhesive")
		(13 "F.Paste" user "Package Geometry/Pastemask Top")
		(15 "B.Paste" user "Package Geometry/Pastemask Bottom")
		(5 "F.SilkS" user "Ref Des/Silkscreen Top")
		(7 "B.SilkS" user "Ref Des/Silkscreen Bottom")
		(1 "F.Mask" user "Board Geometry/Soldermask Top")
		(3 "B.Mask" user "Board Geometry/Soldermask Bottom")
		(17 "Dwgs.User" user "User.Drawings")
		(19 "Cmts.User" user "User.Comments")
		(21 "Eco1.User" user "User.Eco1")
		(23 "Eco2.User" user "User.Eco2")
		(25 "Edge.Cuts" user "Board Geometry/Outline")
		(27 "Margin" user)
		(31 "F.CrtYd" user "Package Geometry/Place Bound Top")
		(29 "B.CrtYd" user "Package Geometry/Place Bound Bottom")
		(35 "F.Fab" user "Ref Des/Assembly Top")
		(33 "B.Fab" user "Ref Des/Assembly Bottom")
	)
	(footprint ""
		(layer "F.Cu")
		(at 463.465926 -96.406208)
		(property "Reference" "R2474"
			(at 0 0 0)
			(layer "F.SilkS")
			(hide yes)
			(effects
				(font
					(size 1.27 1.27)
				)
			)
		)
		(property "Value" ""
			(at 0 0 0)
			(layer "F.Fab")
			(effects
				(font
					(size 1.27 1.27)
				)
			)
		)
		(duplicate_pad_numbers_are_jumpers no)
		(fp_line
			(start -0.7874 -0.4064)
			(end 0.7874 -0.4064)
			(stroke
				(width 0.1524)
				(type default)
			)
			(layer "F.SilkS")
		)
		(fp_line
			(start -0.7874 0.4064)
			(end -0.7874 -0.4064)
			(stroke
				(width 0.1524)
				(type default)
			)
			(layer "F.SilkS")
		)
		(fp_line
			(start 0.7874 -0.4064)
			(end 0.7874 0.4064)
			(stroke
				(width 0.1524)
				(type default)
			)
			(layer "F.SilkS")
		)
		(fp_line
			(start 0.7874 0.4064)
			(end -0.7874 0.4064)
			(stroke
				(width 0.1524)
				(type default)
			)
			(layer "F.SilkS")
		)
		(fp_line
			(start -0.67945 -0.305054)
			(end -0.12065 -0.305054)
			(stroke
				(width 0.1)
				(type default)
			)
			(layer "F.Fab")
		)
		(fp_line
			(start -0.67945 0.3048)
			(end -0.67945 -0.305054)
			(stroke
				(width 0.1)
				(type default)
			)
			(layer "F.Fab")
		)
		(fp_line
			(start -0.12065 -0.305054)
			(end -0.12065 -0.2794)
			(stroke
				(width 0.1)
				(type default)
			)
			(layer "F.Fab")
		)
		(fp_line
			(start -0.12065 -0.2794)
			(end 0.12065 -0.2794)
			(stroke
				(width 0.1)
				(type default)
			)
			(layer "F.Fab")
		)
		(fp_line
			(start -0.12065 0.2794)
			(end -0.12065 0.3048)
			(stroke
				(width 0.1)
				(type default)
			)
			(layer "F.Fab")
		)
		(fp_line
			(start -0.12065 0.3048)
			(end -0.67945 0.3048)
			(stroke
				(width 0.1)
				(type default)
			)
			(layer "F.Fab")
		)
		(fp_line
			(start 0.120396 0.2794)
			(end -0.12065 0.2794)
			(stroke
				(width 0.1)
				(type default)
			)
			(layer "F.Fab")
		)
		(fp_line
			(start 0.120396 0.3048)
			(end 0.120396 0.2794)
			(stroke
				(width 0.1)
				(type default)
			)
			(layer "F.Fab")
		)
		(fp_line
			(start 0.12065 -0.3048)
			(end 0.67945 -0.3048)
			(stroke
				(width 0.1)
				(type default)
			)
			(layer "F.Fab")
		)
		(fp_line
			(start 0.12065 -0.2794)
			(end 0.12065 -0.3048)
			(stroke
				(width 0.1)
				(type default)
			)
			(layer "F.Fab")
		)
		(fp_line
			(start 0.67945 -0.3048)
			(end 0.67945 0.3048)
			(stroke
				(width 0.1)
				(type default)
			)
			(layer "F.Fab")
		)
		(fp_line
			(start 0.67945 0.3048)
			(end 0.120396 0.3048)
			(stroke
				(width 0.1)
				(type default)
			)
			(layer "F.Fab")
		)
		(pad "1" smd circle
			(at -0.40005 0)
			(size 0 0)
			(layers "F.Cu" "F.Mask" "F.Paste")
			(net "FM_NCSI_OCP_SFF_R_OE")
		)
		(pad "2" smd circle
			(at 0.40005 0)
			(size 0 0)
			(layers "F.Cu" "F.Mask" "F.Paste")
			(net "FB_BMC_ISOLATE")
		)
	)
	(footprint ""
		(layer "F.Cu")
		(at 462.20507 -42.004488 90)
		(property "Reference" "R4070"
			(at 0 0 90)
			(layer "F.SilkS")
			(hide yes)
			(effects
				(font
					(size 1.27 1.27)
				)
			)
		)
		(property "Value" ""
			(at 0 0 90)
			(layer "F.Fab")
			(effects
				(font
					(size 1.27 1.27)
				)
			)
		)
		(duplicate_pad_numbers_are_jumpers no)
		(fp_line
			(start 0.7874 -0.4064)
			(end 0.7874 0.4064)
			(stroke
				(width 0.1524)
				(type default)
			)
			(layer "F.SilkS")
		)
		(fp_line
			(start -0.7874 -0.4064)
			(end 0.7874 -0.4064)
			(stroke
				(width 0.1524)
				(type default)
			)
			(layer "F.SilkS")
		)
		(fp_line
			(start 0.7874 0.4064)
			(end -0.7874 0.4064)
			(stroke
				(width 0.1524)
				(type default)
			)
			(layer "F.SilkS")
		)
		(fp_line
			(start -0.7874 0.4064)
			(end -0.7874 -0.4064)
			(stroke
				(width 0.1524)
				(type default)
			)
			(layer "F.SilkS")
		)
		(fp_line
			(start -0.12065 -0.305054)
			(end -0.12065 -0.2794)
			(stroke
				(width 0.1)
				(type default)
			)
			(layer "F.Fab")
		)
		(fp_line
			(start -0.67945 -0.305054)
			(end -0.12065 -0.305054)
			(stroke
				(width 0.1)
				(type default)
			)
			(layer "F.Fab")
		)
		(fp_line
			(start 0.67945 -0.3048)
			(end 0.67945 0.3048)
			(stroke
				(width 0.1)
				(type default)
			)
			(layer "F.Fab")
		)
		(fp_line
			(start 0.12065 -0.3048)
			(end 0.67945 -0.3048)
			(stroke
				(width 0.1)
				(type default)
			)
			(layer "F.Fab")
		)
		(fp_line
			(start 0.12065 -0.2794)
			(end 0.12065 -0.3048)
			(stroke
				(width 0.1)
				(type default)
			)
			(layer "F.Fab")
		)
		(fp_line
			(start -0.12065 -0.2794)
			(end 0.12065 -0.2794)
			(stroke
				(width 0.1)
				(type default)
			)
			(layer "F.Fab")
		)
		(fp_line
			(start 0.120396 0.2794)
			(end -0.12065 0.2794)
			(stroke
				(width 0.1)
				(type default)
			)
			(layer "F.Fab")
		)
		(fp_line
			(start -0.12065 0.2794)
			(end -0.12065 0.3048)
			(stroke
				(width 0.1)
				(type default)
			)
			(layer "F.Fab")
		)
		(fp_line
			(start 0.67945 0.3048)
			(end 0.120396 0.3048)
			(stroke
				(width 0.1)
				(type default)
			)
			(layer "F.Fab")
		)
		(fp_line
			(start 0.120396 0.3048)
			(end 0.120396 0.2794)
			(stroke
				(width 0.1)
				(type default)
			)
			(layer "F.Fab")
		)
		(fp_line
			(start -0.12065 0.3048)
			(end -0.67945 0.3048)
			(stroke
				(width 0.1)
				(type default)
			)
			(layer "F.Fab")
		)
		(fp_line
			(start -0.67945 0.3048)
			(end -0.67945 -0.305054)
			(stroke
				(width 0.1)
				(type default)
			)
			(layer "F.Fab")
		)
		(pad "1" smd circle
			(at -0.40005 0 90)
			(size 0 0)
			(layers "F.Cu" "F.Mask" "F.Paste")
			(net "P12V_AUX")
		)
		(pad "2" smd circle
			(at 0.40005 0 90)
			(size 0 0)
			(layers "F.Cu" "F.Mask" "F.Paste")
			(net "P3V3_OCP_1_EN_G")
		)
	)
)
